# T6G (Grand Teton) — schematic netlist excerpt (pin names and nets, part order shuffled) for the footprints in the layout excerpt that follows; sources: Cadence DE-HDL packaged netlist, KiCad conversion of 04192023_DAF0TMB3IC0_F0TG_MB_C_brd_V02_OCP.brd

R99  Q_RES  1K 1% EMPTY  pkg 0402LF  page 95 : A = P3V3 ; B = PWRGD_CHJ_CPU0_DIMM
R8003  Q_RES  4.7K 5% CHIP  pkg 0402LF  page 123 : A = P3V3_AUX ; B = PRSNT_SWB_ISO_N

(kicad_pcb
	(version 20260206)
	(generator "pcbnew")
	(generator_version "10.0")
	(general
		(thickness 1.6)
		(legacy_teardrops no)
	)
	(paper "A4")
	(title_block
		(title "04192023_DAF0TMB3IC0_F0TG_MB_C_brd_V02_OCP.brd")
		(comment 1 "Grand Teton / footprints 7172-7173 of 8354")
	)
	(layers
		(0 "F.Cu" signal "TOP")
		(4 "In1.Cu" signal "GND")
		(6 "In2.Cu" signal "IN1")
		(8 "In3.Cu" signal "GND1")
		(10 "In4.Cu" signal "IN2")
		(12 "In5.Cu" signal "GND2")
		(14 "In6.Cu" signal "IN3")
		(16 "In7.Cu" signal "GND3")
		(18 "In8.Cu" signal "VCC")
		(20 "In9.Cu" signal "VCC1")
		(22 "In10.Cu" signal "GND4")
		(24 "In11.Cu" signal "IN4")
		(26 "In12.Cu" signal "GND5")
		(28 "In13.Cu" signal "IN5")
		(30 "In14.Cu" signal "GND6")
		(32 "In15.Cu" signal "IN6")
		(34 "In16.Cu" signal "GND7")
		(2 "B.Cu" signal "BOTTOM")
		(9 "F.Adhes" user "F.Adhesive")
		(11 "B.Adhes" user "B.Adhesive")
		(13 "F.Paste" user "Package Geometry/Pastemask Top")
		(15 "B.Paste" user "Package Geometry/Pastemask Bottom")
		(5 "F.SilkS" user "Ref Des/Silkscreen Top")
		(7 "B.SilkS" user "Ref Des/Silkscreen Bottom")
		(1 "F.Mask" user "Board Geometry/Soldermask Top")
		(3 "B.Mask" user "Board Geometry/Soldermask Bottom")
		(17 "Dwgs.User" user "User.Drawings")
		(19 "Cmts.User" user "User.Comments")
		(21 "Eco1.User" user "User.Eco1")
		(23 "Eco2.User" user "User.Eco2")
		(25 "Edge.Cuts" user "Board Geometry/Outline")
		(27 "Margin" user)
		(31 "F.CrtYd" user "Package Geometry/Place Bound Top")
		(29 "B.CrtYd" user "Package Geometry/Place Bound Bottom")
		(35 "F.Fab" user "Ref Des/Assembly Top")
		(33 "B.Fab" user "Ref Des/Assembly Bottom")
	)
	(footprint ""
		(layer "B.Cu")
		(at 435.755796 -193.99631)
		(property "Reference" "R99"
			(at 0 0 0)
			(layer "B.SilkS")
			(hide yes)
			(effects
				(font
					(size 1.27 1.27)
				)
				(justify mirror)
			)
		)
		(property "Value" ""
			(at 0 0 0)
			(layer "B.Fab")
			(effects
				(font
					(size 1.27 1.27)
				)
				(justify mirror)
			)
		)
		(duplicate_pad_numbers_are_jumpers no)
		(fp_line
			(start -0.7874 -0.4064)
			(end -0.7874 0.4064)
			(stroke
				(width 0.1524)
				(type default)
			)
			(layer "B.SilkS")
		)
		(fp_line
			(start -0.7874 0.4064)
			(end 0.7874 0.4064)
			(stroke
				(width 0.1524)
				(type default)
			)
			(layer "B.SilkS")
		)
		(fp_line
			(start 0.7874 -0.4064)
			(end -0.7874 -0.4064)
			(stroke
				(width 0.1524)
				(type default)
			)
			(layer "B.SilkS")
		)
		(fp_line
			(start 0.7874 0.4064)
			(end 0.7874 -0.4064)
			(stroke
				(width 0.1524)
				(type default)
			)
			(layer "B.SilkS")
		)
		(fp_line
			(start -0.67945 -0.3048)
			(end -0.67945 0.3048)
			(stroke
				(width 0.1)
				(type default)
			)
			(layer "B.Fab")
		)
		(fp_line
			(start -0.67945 0.3048)
			(end -0.120396 0.3048)
			(stroke
				(width 0.1)
				(type default)
			)
			(layer "B.Fab")
		)
		(fp_line
			(start -0.12065 -0.3048)
			(end -0.67945 -0.3048)
			(stroke
				(width 0.1)
				(type default)
			)
			(layer "B.Fab")
		)
		(fp_line
			(start -0.12065 -0.2794)
			(end -0.12065 -0.3048)
			(stroke
				(width 0.1)
				(type default)
			)
			(layer "B.Fab")
		)
		(fp_line
			(start -0.120396 0.2794)
			(end 0.12065 0.2794)
			(stroke
				(width 0.1)
				(type default)
			)
			(layer "B.Fab")
		)
		(fp_line
			(start -0.120396 0.3048)
			(end -0.120396 0.2794)
			(stroke
				(width 0.1)
				(type default)
			)
			(layer "B.Fab")
		)
		(fp_line
			(start 0.12065 -0.305054)
			(end 0.12065 -0.2794)
			(stroke
				(width 0.1)
				(type default)
			)
			(layer "B.Fab")
		)
		(fp_line
			(start 0.12065 -0.2794)
			(end -0.12065 -0.2794)
			(stroke
				(width 0.1)
				(type default)
			)
			(layer "B.Fab")
		)
		(fp_line
			(start 0.12065 0.2794)
			(end 0.12065 0.3048)
			(stroke
				(width 0.1)
				(type default)
			)
			(layer "B.Fab")
		)
		(fp_line
			(start 0.12065 0.3048)
			(end 0.67945 0.3048)
			(stroke
				(width 0.1)
				(type default)
			)
			(layer "B.Fab")
		)
		(fp_line
			(start 0.67945 -0.305054)
			(end 0.12065 -0.305054)
			(stroke
				(width 0.1)
				(type default)
			)
			(layer "B.Fab")
		)
		(fp_line
			(start 0.67945 0.3048)
			(end 0.67945 -0.305054)
			(stroke
				(width 0.1)
				(type default)
			)
			(layer "B.Fab")
		)
		(pad "1" smd circle
			(at 0.40005 0 180)
			(size 0 0)
			(layers "B.Cu" "B.Mask" "B.Paste")
			(net "P3V3")
		)
		(pad "2" smd circle
			(at -0.40005 0 180)
			(size 0 0)
			(layers "B.Cu" "B.Mask" "B.Paste")
			(net "PWRGD_CHJ_CPU0_DIMM")
		)
	)
	(footprint ""
		(layer "B.Cu")
		(at 97.591118 -426.179996 180)
		(property "Reference" "R8003"
			(at 0 0 0)
			(layer "B.SilkS")
			(hide yes)
			(effects
				(font
					(size 1.27 1.27)
				)
				(justify mirror)
			)
		)
		(property "Value" ""
			(at 0 0 0)
			(layer "B.Fab")
			(effects
				(font
					(size 1.27 1.27)
				)
				(justify mirror)
			)
		)
		(duplicate_pad_numbers_are_jumpers no)
		(fp_line
			(start 0.7874 0.4064)
			(end 0.7874 -0.4064)
			(stroke
				(width 0.1524)
				(type default)
			)
			(layer "B.SilkS")
		)
		(fp_line
			(start 0.7874 -0.4064)
			(end -0.7874 -0.4064)
			(stroke
				(width 0.1524)
				(type default)
			)
			(layer "B.SilkS")
		)
		(fp_line
			(start -0.7874 0.4064)
			(end 0.7874 0.4064)
			(stroke
				(width 0.1524)
				(type default)
			)
			(layer "B.SilkS")
		)
		(fp_line
			(start -0.7874 -0.4064)
			(end -0.7874 0.4064)
			(stroke
				(width 0.1524)
				(type default)
			)
			(layer "B.SilkS")
		)
		(fp_line
			(start 0.67945 0.3048)
			(end 0.67945 -0.305054)
			(stroke
				(width 0.1)
				(type default)
			)
			(layer "B.Fab")
		)
		(fp_line
			(start 0.67945 -0.305054)
			(end 0.12065 -0.305054)
			(stroke
				(width 0.1)
				(type default)
			)
			(layer "B.Fab")
		)
		(fp_line
			(start 0.12065 0.3048)
			(end 0.67945 0.3048)
			(stroke
				(width 0.1)
				(type default)
			)
			(layer "B.Fab")
		)
		(fp_line
			(start 0.12065 0.2794)
			(end 0.12065 0.3048)
			(stroke
				(width 0.1)
				(type default)
			)
			(layer "B.Fab")
		)
		(fp_line
			(start 0.12065 -0.2794)
			(end -0.12065 -0.2794)
			(stroke
				(width 0.1)
				(type default)
			)
			(layer "B.Fab")
		)
		(fp_line
			(start 0.12065 -0.305054)
			(end 0.12065 -0.2794)
			(stroke
				(width 0.1)
				(type default)
			)
			(layer "B.Fab")
		)
		(fp_line
			(start -0.120396 0.3048)
			(end -0.120396 0.2794)
			(stroke
				(width 0.1)
				(type default)
			)
			(layer "B.Fab")
		)
		(fp_line
			(start -0.120396 0.2794)
			(end 0.12065 0.2794)
			(stroke
				(width 0.1)
				(type default)
			)
			(layer "B.Fab")
		)
		(fp_line
			(start -0.12065 -0.2794)
			(end -0.12065 -0.3048)
			(stroke
				(width 0.1)
				(type default)
			)
			(layer "B.Fab")
		)
		(fp_line
			(start -0.12065 -0.3048)
			(end -0.67945 -0.3048)
			(stroke
				(width 0.1)
				(type default)
			)
			(layer "B.Fab")
		)
		(fp_line
			(start -0.67945 0.3048)
			(end -0.120396 0.3048)
			(stroke
				(width 0.1)
				(type default)
			)
			(layer "B.Fab")
		)
		(fp_line
			(start -0.67945 -0.3048)
			(end -0.67945 0.3048)
			(stroke
				(width 0.1)
				(type default)
			)
			(layer "B.Fab")
		)
		(pad "1" smd circle
			(at 0.40005 0)
			(size 0 0)
			(layers "B.Cu" "B.Mask" "B.Paste")
			(net "P3V3_AUX")
		)
		(pad "2" smd circle
			(at -0.40005 0)
			(size 0 0)
			(layers "B.Cu" "B.Mask" "B.Paste")
			(net "PRSNT_SWB_ISO_N")
		)
	)
)
